# BARRELEYE_G2-FPDB_POST-EVT-HW-EBOM-X00_20161123-add_2nd_source_X08-20161215-Final-b.xls — TBD AVL Qual (bom)
| NOTES: |  |  |  |  |  |  |
| The following items are alternates to the items listed in the Critical Components Qual tab. |  |  |  |  |  |  |
| These components will be included on near future, non-customer builds for validation and approval by both Customer and the ODM. |  |  |  |  |  |  |
| Item Description | ODM P/N | Customer PN | Vendor | Vendor PN | Build ?? | Estimated Completion Date |
| SATA connectors (black) |  |  |  |  |  |  |
| -  Alternate |  |  |  |  |  |  |
| SATA connectors (blue) |  |  |  |  |  |  |
| -  Alternate |  |  |  |  |  |  |
| PCIe retention |  |  |  |  |  |  |
| -  Alternate |  |  |  |  |  |  |
| RTC XTAL |  |  |  |  |  |  |
| -  Alternate |  |  |  |  |  |  |
| XTAL |  |  |  |  |  |  |
| -  Alternate |  |  |  |  |  |  |
